(kicad_pcb
	(version 20260206)
	(generator "pcbnew")
	(generator_version "10.0")
	(general
		(thickness 1.6)
		(legacy_teardrops no)
	)
	(paper "A4")
	(title_block
		(title "pdpb — Lightning_PDPB_BRD.brd")
		(comment 1 "Lightning (Wiwynn / Facebook NVMe JBOF) / footprints 1007-1013 of 1140")
	)
	(layers
		(0 "F.Cu" signal "TOP")
		(4 "In1.Cu" signal "L2GND")
		(6 "In2.Cu" signal "L3")
		(8 "In3.Cu" signal "L4VCC")
		(10 "In4.Cu" signal "L5VCC")
		(12 "In5.Cu" signal "L6")
		(14 "In6.Cu" signal "L7GND")
		(2 "B.Cu" signal "BOTTOM")
		(9 "F.Adhes" user "F.Adhesive")
		(11 "B.Adhes" user "B.Adhesive")
		(13 "F.Paste" user "Package Geometry/Pastemask Top")
		(15 "B.Paste" user "Package Geometry/Pastemask Bottom")
		(5 "F.SilkS" user "Ref Des/Silkscreen Top")
		(7 "B.SilkS" user "Ref Des/Silkscreen Bottom")
		(1 "F.Mask" user "Board Geometry/Soldermask Top")
		(3 "B.Mask" user "Board Geometry/Soldermask Bottom")
		(17 "Dwgs.User" user "User.Drawings")
		(19 "Cmts.User" user "User.Comments")
		(21 "Eco1.User" user "User.Eco1")
		(23 "Eco2.User" user "User.Eco2")
		(25 "Edge.Cuts" user "Board Geometry/Outline")
		(27 "Margin" user)
		(31 "F.CrtYd" user "Package Geometry/Place Bound Top")
		(29 "B.CrtYd" user "Package Geometry/Place Bound Bottom")
		(35 "F.Fab" user "Ref Des/Assembly Top")
		(33 "B.Fab" user "Ref Des/Assembly Bottom")
	)
	(footprint ""
		(layer "F.Cu")
		(at 7.9248 -451.8279 -90)
		(property "Reference" "C9541"
			(at 0 0 270)
			(layer "F.SilkS")
			(hide yes)
			(effects
				(font
					(size 1.27 1.27)
				)
			)
		)
		(property "Value" "SCD01U50V2KX-1GP"
			(at 1.1811 -2.7051 270)
			(unlocked yes)
			(layer "F.Fab")
			(hide yes)
			(effects
				(font
					(size 1.016 1.016)
					(thickness 0.1524)
				)
			)
		)
		(property "Device Type" "C402H22"
			(at 1.1811 -4.2291 270)
			(unlocked yes)
			(layer "F.Fab")
			(hide yes)
			(effects
				(font
					(size 1.016 1.016)
					(thickness 0.1524)
				)
			)
		)
		(duplicate_pad_numbers_are_jumpers no)
		(fp_rect
			(start -0.4318 0.9525)
			(end 0.4318 -0.9525)
			(stroke
				(width 0)
				(type default)
			)
			(fill no)
			(layer "F.CrtYd")
		)
		(fp_rect
			(start -0.4318 0.9525)
			(end 0.4318 -0.9525)
			(stroke
				(width 0)
				(type default)
			)
			(fill no)
			(layer "F.Fab")
		)
		(pad "1" smd custom
			(at 0 -0.4445 270)
			(size 0.1524 0.1524)
			(layers "F.Cu" "F.Mask" "F.Paste")
			(net "PE_100M_CLK4_N")
			(options
				(clearance outline)
				(anchor circle)
			)
			(primitives
				(gr_poly
					(pts
						(arc
							(start 0.3048 -0.2032)
							(mid 0.275042 -0.275042)
							(end 0.2032 -0.3048)
						)
						(arc
							(start -0.2032 -0.3048)
							(mid -0.275042 -0.275042)
							(end -0.3048 -0.2032)
						)
						(arc
							(start -0.3048 0.2032)
							(mid -0.275042 0.275042)
							(end -0.2032 0.3048)
						)
						(arc
							(start 0.2032 0.3048)
							(mid 0.275042 0.275042)
							(end 0.3048 0.2032)
						)
					)
					(width 0)
					(fill yes)
				)
			)
		)
		(pad "2" smd custom
			(at 0 0.4445 270)
			(size 0.1524 0.1524)
			(layers "F.Cu" "F.Mask" "F.Paste")
			(net "PE_100M_CLK4_C_N")
			(options
				(clearance outline)
				(anchor circle)
			)
			(primitives
				(gr_poly
					(pts
						(arc
							(start 0.3048 -0.2032)
							(mid 0.275042 -0.275042)
							(end 0.2032 -0.3048)
						)
						(arc
							(start -0.2032 -0.3048)
							(mid -0.275042 -0.275042)
							(end -0.3048 -0.2032)
						)
						(arc
							(start -0.3048 0.2032)
							(mid -0.275042 0.275042)
							(end -0.2032 0.3048)
						)
						(arc
							(start 0.2032 0.3048)
							(mid 0.275042 0.275042)
							(end 0.3048 0.2032)
						)
					)
					(width 0)
					(fill yes)
				)
			)
		)
	)
	(footprint ""
		(layer "F.Cu")
		(at 102.616 -311.531 90)
		(property "Reference" "R9073"
			(at 0 0 90)
			(layer "F.SilkS")
			(hide yes)
			(effects
				(font
					(size 1.27 1.27)
				)
			)
		)
		(property "Value" "27R2F-GP"
			(at 0.064008 -3.993896 90)
			(unlocked yes)
			(layer "F.Fab")
			(hide yes)
			(effects
				(font
					(size 1.016 1.016)
					(thickness 0.1524)
				)
			)
		)
		(property "Device Type" "R402H16"
			(at 0.064008 -5.517896 90)
			(unlocked yes)
			(layer "F.Fab")
			(hide yes)
			(effects
				(font
					(size 1.016 1.016)
					(thickness 0.1524)
				)
			)
		)
		(duplicate_pad_numbers_are_jumpers no)
		(fp_line
			(start 0.508 -0.9398)
			(end -0.508 -0.9398)
			(stroke
				(width 0.1524)
				(type default)
			)
			(layer "F.SilkS")
		)
		(fp_line
			(start -0.508 -0.9398)
			(end -0.508 0.9398)
			(stroke
				(width 0.1524)
				(type default)
			)
			(layer "F.SilkS")
		)
		(fp_rect
			(start -0.508 0.9398)
			(end 0.508 -0.9398)
			(stroke
				(width 0)
				(type default)
			)
			(fill no)
			(layer "F.CrtYd")
		)
		(fp_rect
			(start -0.508 0.9398)
			(end 0.508 -0.9398)
			(stroke
				(width 0)
				(type default)
			)
			(fill no)
			(layer "F.Fab")
		)
		(pad "1" smd custom
			(at 0 -0.4445 90)
			(size 0.1397 0.1397)
			(layers "F.Cu" "F.Mask" "F.Paste")
			(net "PE_CLK_100M_DR1_1_R_N")
			(options
				(clearance outline)
				(anchor circle)
			)
			(primitives
				(gr_poly
					(pts
						(arc
							(start -0.1778 -0.2794)
							(mid -0.249642 -0.249642)
							(end -0.2794 -0.1778)
						)
						(arc
							(start -0.2794 0.1778)
							(mid -0.249642 0.249642)
							(end -0.1778 0.2794)
						)
						(arc
							(start 0.1778 0.2794)
							(mid 0.249642 0.249642)
							(end 0.2794 0.1778)
						)
						(arc
							(start 0.2794 -0.1778)
							(mid 0.249642 -0.249642)
							(end 0.1778 -0.2794)
						)
					)
					(width 0)
					(fill yes)
				)
			)
		)
		(pad "2" smd custom
			(at 0 0.4445 90)
			(size 0.1397 0.1397)
			(layers "F.Cu" "F.Mask" "F.Paste")
			(net "PE_CLK100M_DR1_1_N")
			(options
				(clearance outline)
				(anchor circle)
			)
			(primitives
				(gr_poly
					(pts
						(arc
							(start -0.1778 -0.2794)
							(mid -0.249642 -0.249642)
							(end -0.2794 -0.1778)
						)
						(arc
							(start -0.2794 0.1778)
							(mid -0.249642 0.249642)
							(end -0.1778 0.2794)
						)
						(arc
							(start 0.1778 0.2794)
							(mid 0.249642 0.249642)
							(end 0.2794 0.1778)
						)
						(arc
							(start 0.2794 -0.1778)
							(mid 0.249642 -0.249642)
							(end 0.1778 -0.2794)
						)
					)
					(width 0)
					(fill yes)
				)
			)
		)
	)
	(footprint ""
		(layer "F.Cu")
		(at 21.8694 -466.4202 90)
		(property "Reference" "R9922"
			(at 0 0 90)
			(layer "F.SilkS")
			(hide yes)
			(effects
				(font
					(size 1.27 1.27)
				)
			)
		)
		(property "Value" "47KR2J-2-GP"
			(at 0.064008 -3.993896 90)
			(unlocked yes)
			(layer "F.Fab")
			(hide yes)
			(effects
				(font
					(size 1.016 1.016)
					(thickness 0.1524)
				)
			)
		)
		(property "Device Type" "R402H16"
			(at 0.064008 -5.517896 90)
			(unlocked yes)
			(layer "F.Fab")
			(hide yes)
			(effects
				(font
					(size 1.016 1.016)
					(thickness 0.1524)
				)
			)
		)
		(duplicate_pad_numbers_are_jumpers no)
		(fp_line
			(start 0.508 -0.9398)
			(end -0.508 -0.9398)
			(stroke
				(width 0.1524)
				(type default)
			)
			(layer "F.SilkS")
		)
		(fp_line
			(start -0.508 -0.9398)
			(end -0.508 0.9398)
			(stroke
				(width 0.1524)
				(type default)
			)
			(layer "F.SilkS")
		)
		(fp_rect
			(start -0.508 0.9398)
			(end 0.508 -0.9398)
			(stroke
				(width 0)
				(type default)
			)
			(fill no)
			(layer "F.CrtYd")
		)
		(fp_rect
			(start -0.508 0.9398)
			(end 0.508 -0.9398)
			(stroke
				(width 0)
				(type default)
			)
			(fill no)
			(layer "F.Fab")
		)
		(pad "1" smd custom
			(at 0 -0.4445 90)
			(size 0.1397 0.1397)
			(layers "F.Cu" "F.Mask" "F.Paste")
			(net "P3V3")
			(options
				(clearance outline)
				(anchor circle)
			)
			(primitives
				(gr_poly
					(pts
						(arc
							(start -0.1778 -0.2794)
							(mid -0.249642 -0.249642)
							(end -0.2794 -0.1778)
						)
						(arc
							(start -0.2794 0.1778)
							(mid -0.249642 0.249642)
							(end -0.1778 0.2794)
						)
						(arc
							(start 0.1778 0.2794)
							(mid 0.249642 0.249642)
							(end 0.2794 0.1778)
						)
						(arc
							(start 0.2794 -0.1778)
							(mid 0.249642 -0.249642)
							(end 0.1778 -0.2794)
						)
					)
					(width 0)
					(fill yes)
				)
			)
		)
		(pad "2" smd custom
			(at 0 0.4445 90)
			(size 0.1397 0.1397)
			(layers "F.Cu" "F.Mask" "F.Paste")
			(net "ATTN_LED_DR10_N")
			(options
				(clearance outline)
				(anchor circle)
			)
			(primitives
				(gr_poly
					(pts
						(arc
							(start -0.1778 -0.2794)
							(mid -0.249642 -0.249642)
							(end -0.2794 -0.1778)
						)
						(arc
							(start -0.2794 0.1778)
							(mid -0.249642 0.249642)
							(end -0.1778 0.2794)
						)
						(arc
							(start 0.1778 0.2794)
							(mid 0.249642 0.249642)
							(end 0.2794 0.1778)
						)
						(arc
							(start 0.2794 -0.1778)
							(mid 0.249642 -0.249642)
							(end 0.1778 -0.2794)
						)
					)
					(width 0)
					(fill yes)
				)
			)
		)
	)
	(footprint ""
		(layer "F.Cu")
		(at 100.33 -219.456 180)
		(property "Reference" "R9095"
			(at 0 0 180)
			(layer "F.SilkS")
			(hide yes)
			(effects
				(font
					(size 1.27 1.27)
				)
			)
		)
		(property "Value" "27R2F-GP"
			(at 0.064008 -3.993896 180)
			(unlocked yes)
			(layer "F.Fab")
			(hide yes)
			(effects
				(font
					(size 1.016 1.016)
					(thickness 0.1524)
				)
			)
		)
		(property "Device Type" "R402H16"
			(at 0.064008 -5.517896 180)
			(unlocked yes)
			(layer "F.Fab")
			(hide yes)
			(effects
				(font
					(size 1.016 1.016)
					(thickness 0.1524)
				)
			)
		)
		(duplicate_pad_numbers_are_jumpers no)
		(fp_line
			(start 0.508 -0.9398)
			(end -0.508 -0.9398)
			(stroke
				(width 0.1524)
				(type default)
			)
			(layer "F.SilkS")
		)
		(fp_line
			(start -0.508 -0.9398)
			(end -0.508 0.9398)
			(stroke
				(width 0.1524)
				(type default)
			)
			(layer "F.SilkS")
		)
		(fp_rect
			(start -0.508 0.9398)
			(end 0.508 -0.9398)
			(stroke
				(width 0)
				(type default)
			)
			(fill no)
			(layer "F.CrtYd")
		)
		(fp_rect
			(start -0.508 0.9398)
			(end 0.508 -0.9398)
			(stroke
				(width 0)
				(type default)
			)
			(fill no)
			(layer "F.Fab")
		)
		(pad "1" smd custom
			(at 0 -0.4445 180)
			(size 0.1397 0.1397)
			(layers "F.Cu" "F.Mask" "F.Paste")
			(net "PE_CLK_100M_DR7_2_R_P")
			(options
				(clearance outline)
				(anchor circle)
			)
			(primitives
				(gr_poly
					(pts
						(arc
							(start -0.1778 -0.2794)
							(mid -0.249642 -0.249642)
							(end -0.2794 -0.1778)
						)
						(arc
							(start -0.2794 0.1778)
							(mid -0.249642 0.249642)
							(end -0.1778 0.2794)
						)
						(arc
							(start 0.1778 0.2794)
							(mid 0.249642 0.249642)
							(end 0.2794 0.1778)
						)
						(arc
							(start 0.2794 -0.1778)
							(mid 0.249642 -0.249642)
							(end 0.1778 -0.2794)
						)
					)
					(width 0)
					(fill yes)
				)
			)
		)
		(pad "2" smd custom
			(at 0 0.4445 180)
			(size 0.1397 0.1397)
			(layers "F.Cu" "F.Mask" "F.Paste")
			(net "PE_CLK100M_DR7_2_P")
			(options
				(clearance outline)
				(anchor circle)
			)
			(primitives
				(gr_poly
					(pts
						(arc
							(start -0.1778 -0.2794)
							(mid -0.249642 -0.249642)
							(end -0.2794 -0.1778)
						)
						(arc
							(start -0.2794 0.1778)
							(mid -0.249642 0.249642)
							(end -0.1778 0.2794)
						)
						(arc
							(start 0.1778 0.2794)
							(mid 0.249642 0.249642)
							(end 0.2794 0.1778)
						)
						(arc
							(start 0.2794 -0.1778)
							(mid 0.249642 -0.249642)
							(end 0.1778 -0.2794)
						)
					)
					(width 0)
					(fill yes)
				)
			)
		)
	)
	(footprint ""
		(layer "F.Cu")
		(at 70.739 -363.601 90)
		(property "Reference" "SR979"
			(at 0 0 90)
			(layer "F.SilkS")
			(hide yes)
			(effects
				(font
					(size 1.27 1.27)
				)
			)
		)
		(property "Value" "2KR2F-3-GP"
			(at 0.064008 -3.993896 90)
			(unlocked yes)
			(layer "F.Fab")
			(hide yes)
			(effects
				(font
					(size 1.016 1.016)
					(thickness 0.1524)
				)
			)
		)
		(property "Device Type" "R402H16"
			(at 0.064008 -5.517896 90)
			(unlocked yes)
			(layer "F.Fab")
			(hide yes)
			(effects
				(font
					(size 1.016 1.016)
					(thickness 0.1524)
				)
			)
		)
		(duplicate_pad_numbers_are_jumpers no)
		(fp_line
			(start 0.508 -0.9398)
			(end -0.508 -0.9398)
			(stroke
				(width 0.1524)
				(type default)
			)
			(layer "F.SilkS")
		)
		(fp_line
			(start -0.508 -0.9398)
			(end -0.508 0.9398)
			(stroke
				(width 0.1524)
				(type default)
			)
			(layer "F.SilkS")
		)
		(fp_rect
			(start -0.508 0.9398)
			(end 0.508 -0.9398)
			(stroke
				(width 0)
				(type default)
			)
			(fill no)
			(layer "F.CrtYd")
		)
		(fp_rect
			(start -0.508 0.9398)
			(end 0.508 -0.9398)
			(stroke
				(width 0)
				(type default)
			)
			(fill no)
			(layer "F.Fab")
		)
		(pad "1" smd custom
			(at 0 -0.4445 90)
			(size 0.1397 0.1397)
			(layers "F.Cu" "F.Mask" "F.Paste")
			(net "P3V3")
			(options
				(clearance outline)
				(anchor circle)
			)
			(primitives
				(gr_poly
					(pts
						(arc
							(start -0.1778 -0.2794)
							(mid -0.249642 -0.249642)
							(end -0.2794 -0.1778)
						)
						(arc
							(start -0.2794 0.1778)
							(mid -0.249642 0.249642)
							(end -0.1778 0.2794)
						)
						(arc
							(start 0.1778 0.2794)
							(mid 0.249642 0.249642)
							(end 0.2794 0.1778)
						)
						(arc
							(start 0.2794 -0.1778)
							(mid 0.249642 -0.249642)
							(end 0.1778 -0.2794)
						)
					)
					(width 0)
					(fill yes)
				)
			)
		)
		(pad "2" smd custom
			(at 0 0.4445 90)
			(size 0.1397 0.1397)
			(layers "F.Cu" "F.Mask" "F.Paste")
			(net "SDA_DR11")
			(options
				(clearance outline)
				(anchor circle)
			)
			(primitives
				(gr_poly
					(pts
						(arc
							(start -0.1778 -0.2794)
							(mid -0.249642 -0.249642)
							(end -0.2794 -0.1778)
						)
						(arc
							(start -0.2794 0.1778)
							(mid -0.249642 0.249642)
							(end -0.1778 0.2794)
						)
						(arc
							(start 0.1778 0.2794)
							(mid 0.249642 0.249642)
							(end 0.2794 0.1778)
						)
						(arc
							(start 0.2794 -0.1778)
							(mid 0.249642 -0.249642)
							(end 0.1778 -0.2794)
						)
					)
					(width 0)
					(fill yes)
				)
			)
		)
	)
	(footprint ""
		(layer "F.Cu")
		(at 39.243 -136.144)
		(property "Reference" "TP5"
			(at 0 0 0)
			(layer "F.SilkS")
			(hide yes)
			(effects
				(font
					(size 1.27 1.27)
				)
			)
		)
		(property "Value" "TPAD32-GP"
			(at -0.0508 -1.6764 0)
			(unlocked yes)
			(layer "F.Fab")
			(hide yes)
			(effects
				(font
					(size 1.016 1.016)
					(thickness 0.1524)
				)
			)
		)
		(property "Device Type" "TPAD32"
			(at -0.0508 -3.2004 0)
			(unlocked yes)
			(layer "F.Fab")
			(hide yes)
			(effects
				(font
					(size 1.016 1.016)
					(thickness 0.1524)
				)
			)
		)
		(duplicate_pad_numbers_are_jumpers no)
		(fp_poly
			(pts
				(arc
					(start 0.4064 0)
					(mid -0.4064 0)
					(end 0.4064 0)
				)
			)
			(stroke
				(width 0)
				(type default)
			)
			(fill no)
			(layer "F.CrtYd")
		)
		(fp_poly
			(pts
				(arc
					(start 0.7112 0)
					(mid -0.7112 0)
					(end 0.7112 0)
				)
			)
			(stroke
				(width 0)
				(type default)
			)
			(fill no)
			(layer "F.Fab")
		)
		(pad "1" smd circle
			(at 0 0)
			(size 0.8128 0.8128)
			(layers "F.Cu" "F.Mask" "F.Paste")
			(net "I2C_B_TMP1_ALERT")
		)
	)
	(footprint ""
		(layer "F.Cu")
		(at 23.1648 -293.2176)
		(property "Reference" "R558"
			(at 0 0 0)
			(layer "F.SilkS")
			(hide yes)
			(effects
				(font
					(size 1.27 1.27)
				)
			)
		)
		(property "Value" "200KR2F-L-GP"
			(at 0.064008 -3.993896 0)
			(unlocked yes)
			(layer "F.Fab")
			(hide yes)
			(effects
				(font
					(size 1.016 1.016)
					(thickness 0.1524)
				)
			)
		)
		(property "Device Type" "R402H16"
			(at 0.064008 -5.517896 0)
			(unlocked yes)
			(layer "F.Fab")
			(hide yes)
			(effects
				(font
					(size 1.016 1.016)
					(thickness 0.1524)
				)
			)
		)
		(duplicate_pad_numbers_are_jumpers no)
		(fp_line
			(start -0.508 -0.9398)
			(end -0.508 0.9398)
			(stroke
				(width 0.1524)
				(type default)
			)
			(layer "F.SilkS")
		)
		(fp_line
			(start 0.508 -0.9398)
			(end -0.508 -0.9398)
			(stroke
				(width 0.1524)
				(type default)
			)
			(layer "F.SilkS")
		)
		(fp_rect
			(start -0.508 0.9398)
			(end 0.508 -0.9398)
			(stroke
				(width 0)
				(type default)
			)
			(fill no)
			(layer "F.CrtYd")
		)
		(fp_rect
			(start -0.508 0.9398)
			(end 0.508 -0.9398)
			(stroke
				(width 0)
				(type default)
			)
			(fill no)
			(layer "F.Fab")
		)
		(pad "1" smd custom
			(at 0 -0.4445)
			(size 0.1397 0.1397)
			(layers "F.Cu" "F.Mask" "F.Paste")
			(net "SW_SSD7_R")
			(options
				(clearance outline)
				(anchor circle)
			)
			(primitives
				(gr_poly
					(pts
						(arc
							(start -0.1778 -0.2794)
							(mid -0.249642 -0.249642)
							(end -0.2794 -0.1778)
						)
						(arc
							(start -0.2794 0.1778)
							(mid -0.249642 0.249642)
							(end -0.1778 0.2794)
						)
						(arc
							(start 0.1778 0.2794)
							(mid 0.249642 0.249642)
							(end 0.2794 0.1778)
						)
						(arc
							(start 0.2794 -0.1778)
							(mid 0.249642 -0.249642)
							(end 0.1778 -0.2794)
						)
					)
					(width 0)
					(fill yes)
				)
			)
		)
		(pad "2" smd custom
			(at 0 0.4445)
			(size 0.1397 0.1397)
			(layers "F.Cu" "F.Mask" "F.Paste")
			(net "SW_SSD7_N")
			(options
				(clearance outline)
				(anchor circle)
			)
			(primitives
				(gr_poly
					(pts
						(arc
							(start -0.1778 -0.2794)
							(mid -0.249642 -0.249642)
							(end -0.2794 -0.1778)
						)
						(arc
							(start -0.2794 0.1778)
							(mid -0.249642 0.249642)
							(end -0.1778 0.2794)
						)
						(arc
							(start 0.1778 0.2794)
							(mid 0.249642 0.249642)
							(end 0.2794 0.1778)
						)
						(arc
							(start 0.2794 -0.1778)
							(mid 0.249642 -0.249642)
							(end 0.1778 -0.2794)
						)
					)
					(width 0)
					(fill yes)
				)
			)
		)
	)
)
